(kicad_pcb
	(version 20260206)
	(generator "pcbnew")
	(generator_version "10.0")
	(general
		(thickness 1.6)
		(legacy_teardrops no)
	)
	(paper "A4")
	(title_block
		(title "01162023_DA0F0TEBIF0_F0T_Expander_BD_F_brd_V02_OCP.brd")
		(comment 1 "Grand Teton / footprints 341-346 of 9728")
	)
	(layers
		(0 "F.Cu" signal "TOP")
		(4 "In1.Cu" signal "GND")
		(6 "In2.Cu" signal "VCC")
		(8 "In3.Cu" signal "VCC1")
		(10 "In4.Cu" signal "GND1")
		(12 "In5.Cu" signal "IN1")
		(14 "In6.Cu" signal "GND2")
		(16 "In7.Cu" signal "IN2")
		(18 "In8.Cu" signal "GND3")
		(20 "In9.Cu" signal "IN3")
		(22 "In10.Cu" signal "GND4")
		(24 "In11.Cu" signal "IN4")
		(26 "In12.Cu" signal "GND5")
		(28 "In13.Cu" signal "IN5")
		(30 "In14.Cu" signal "GND6")
		(32 "In15.Cu" signal "IN6")
		(34 "In16.Cu" signal "GND7")
		(2 "B.Cu" signal "BOTTOM")
		(9 "F.Adhes" user "F.Adhesive")
		(11 "B.Adhes" user "B.Adhesive")
		(13 "F.Paste" user "Package Geometry/Pastemask Top")
		(15 "B.Paste" user "Package Geometry/Pastemask Bottom")
		(5 "F.SilkS" user "Ref Des/Silkscreen Top")
		(7 "B.SilkS" user "Ref Des/Silkscreen Bottom")
		(1 "F.Mask" user "Board Geometry/Soldermask Top")
		(3 "B.Mask" user "Board Geometry/Soldermask Bottom")
		(17 "Dwgs.User" user "User.Drawings")
		(19 "Cmts.User" user "User.Comments")
		(21 "Eco1.User" user "User.Eco1")
		(23 "Eco2.User" user "User.Eco2")
		(25 "Edge.Cuts" user "Board Geometry/Outline")
		(27 "Margin" user)
		(31 "F.CrtYd" user "Package Geometry/Place Bound Top")
		(29 "B.CrtYd" user "Package Geometry/Place Bound Bottom")
		(35 "F.Fab" user "Ref Des/Assembly Top")
		(33 "B.Fab" user "Ref Des/Assembly Bottom")
	)
	(footprint ""
		(layer "F.Cu")
		(at 58.890916 -55.663846 90)
		(property "Reference" "PU59"
			(at -1.120394 3.012186 90)
			(unlocked yes)
			(layer "F.SilkS")
			(effects
				(font
					(size 0.7874 0.5842)
					(thickness 0.1524)
				)
				(justify left)
			)
		)
		(property "Value" ""
			(at 0 0 90)
			(layer "F.Fab")
			(effects
				(font
					(size 1.27 1.27)
				)
			)
		)
		(duplicate_pad_numbers_are_jumpers no)
		(fp_line
			(start 1.943608 -1.549908)
			(end 1.943608 1.549908)
			(stroke
				(width 0.1524)
				(type default)
			)
			(layer "F.SilkS")
		)
		(fp_line
			(start -1.943608 -1.549908)
			(end 1.943608 -1.549908)
			(stroke
				(width 0.1524)
				(type default)
			)
			(layer "F.SilkS")
		)
		(fp_line
			(start 1.943608 1.549908)
			(end -1.943608 1.549908)
			(stroke
				(width 0.1524)
				(type default)
			)
			(layer "F.SilkS")
		)
		(fp_line
			(start -1.943608 1.549908)
			(end -1.943608 -1.549908)
			(stroke
				(width 0.1524)
				(type default)
			)
			(layer "F.SilkS")
		)
		(fp_poly
			(pts
				(xy -2.019808 -1.549908) (xy -1.257808 -1.549908) (xy -1.257808 -1.880108) (xy -2.019808 -1.880108)
			)
			(stroke
				(width 0)
				(type default)
			)
			(fill yes)
			(layer "F.SilkS")
		)
		(fp_line
			(start 1.549908 -1.549908)
			(end 1.549908 1.549908)
			(stroke
				(width 0.1)
				(type default)
			)
			(layer "F.Fab")
		)
		(fp_line
			(start -1.549908 -1.549908)
			(end 1.549908 -1.549908)
			(stroke
				(width 0.1)
				(type default)
			)
			(layer "F.Fab")
		)
		(fp_line
			(start 1.549908 1.549908)
			(end -1.549908 1.549908)
			(stroke
				(width 0.1)
				(type default)
			)
			(layer "F.Fab")
		)
		(fp_line
			(start -1.549908 1.549908)
			(end -1.549908 -1.549908)
			(stroke
				(width 0.1)
				(type default)
			)
			(layer "F.Fab")
		)
		(fp_poly
			(pts
				(xy -2.019808 -1.549908) (xy -1.257808 -1.549908) (xy -1.257808 -1.880108) (xy -2.019808 -1.880108)
			)
			(stroke
				(width 0)
				(type default)
			)
			(fill yes)
			(layer "F.Fab")
		)
		(pad "1" smd rect
			(at -1.500124 -1.249934)
			(size 0.2794 0.6096)
			(layers "F.Cu" "F.Mask" "F.Paste")
			(net "P3V3_SSD2")
		)
		(pad "2" smd rect
			(at -1.500124 -0.750062)
			(size 0.2794 0.6096)
			(layers "F.Cu" "F.Mask" "F.Paste")
			(net "P3V3_SSD2")
		)
		(pad "3" smd rect
			(at -1.500124 -0.249936)
			(size 0.2794 0.6096)
			(layers "F.Cu" "F.Mask" "F.Paste")
			(net "P3V3_SSD2")
		)
		(pad "4" smd rect
			(at -1.500124 0.249936)
			(size 0.2794 0.6096)
			(layers "F.Cu" "F.Mask" "F.Paste")
			(net "P3V3_SSD2")
		)
		(pad "5" smd rect
			(at -1.500124 0.750062)
			(size 0.2794 0.6096)
			(layers "F.Cu" "F.Mask" "F.Paste")
			(net "P3V3_SSD2")
		)
		(pad "6" smd rect
			(at -1.500124 1.249934)
			(size 0.2794 0.6096)
			(layers "F.Cu" "F.Mask" "F.Paste")
			(net "GND")
		)
		(pad "7" smd rect
			(at 1.500124 1.249934)
			(size 0.2794 0.6096)
			(layers "F.Cu" "F.Mask" "F.Paste")
			(net "P3V3_SSD2_SS")
		)
		(pad "8" smd rect
			(at 1.500124 0.750062)
			(size 0.2794 0.6096)
			(layers "F.Cu" "F.Mask" "F.Paste")
			(net "PWRGD_P3V3_SSD2")
		)
		(pad "9" smd rect
			(at 1.500124 0.249936)
			(size 0.2794 0.6096)
			(layers "F.Cu" "F.Mask" "F.Paste")
			(net "P3V3_SSD2_OCP")
		)
		(pad "10" smd rect
			(at 1.500124 -0.249936)
			(size 0.2794 0.6096)
			(layers "F.Cu" "F.Mask" "F.Paste")
			(net "P5V_AUX")
		)
		(pad "11" smd rect
			(at 1.500124 -0.750062)
			(size 0.2794 0.6096)
			(layers "F.Cu" "F.Mask" "F.Paste")
			(net "SSD2_AUX_P3V3_EN_R")
		)
		(pad "12" smd rect
			(at 1.500124 -1.249934)
			(size 0.2794 0.6096)
			(layers "F.Cu" "F.Mask" "F.Paste")
			(net "P3V3_AUX")
		)
		(pad "13" smd rect
			(at 0 0 90)
			(size 1.9812 2.7178)
			(layers "F.Cu" "F.Mask" "F.Paste")
			(net "P3V3_AUX")
		)
		(zone
			(layer "F.Cu")
			(hatch none 0.5)
			(connect_pads
				(clearance 0)
			)
			(min_thickness 0.25)
			(keepout
				(tracks not_allowed)
				(vias allowed)
				(pads allowed)
				(copperpour not_allowed)
				(footprints allowed)
			)
			(placement
				(enabled no)
				(sheetname "")
			)
			(fill
				(thermal_gap 0.5)
				(thermal_bridge_width 0.5)
				(island_removal_mode 0)
			)
			(polygon
				(pts
					(xy 57.341516 -56.806846) (xy 57.468516 -56.806846) (xy 60.440316 -56.806846) (xy 60.440824 -56.806846)
					(xy 60.440824 -54.520846) (xy 60.440316 -54.520846) (xy 60.313316 -54.520846) (xy 58.890916 -54.520846)
					(xy 58.890916 -54.622446) (xy 60.313316 -54.622446) (xy 60.313316 -56.705246) (xy 57.468516 -56.705246)
					(xy 57.468516 -54.622446) (xy 58.865516 -54.622446) (xy 58.865516 -54.520846) (xy 57.468516 -54.520846)
					(xy 57.341516 -54.520846) (xy 57.341008 -54.520846) (xy 57.341008 -56.806846)
				)
			)
		)
	)
	(footprint ""
		(layer "F.Cu")
		(at 214.614506 -66.32194 90)
		(property "Reference" "R5981"
			(at 0 0 90)
			(layer "F.SilkS")
			(hide yes)
			(effects
				(font
					(size 1.27 1.27)
				)
			)
		)
		(property "Value" ""
			(at 0 0 90)
			(layer "F.Fab")
			(effects
				(font
					(size 1.27 1.27)
				)
			)
		)
		(duplicate_pad_numbers_are_jumpers no)
		(fp_line
			(start 0.7874 -0.4064)
			(end 0.7874 0.4064)
			(stroke
				(width 0.1524)
				(type default)
			)
			(layer "F.SilkS")
		)
		(fp_line
			(start -0.7874 -0.4064)
			(end 0.7874 -0.4064)
			(stroke
				(width 0.1524)
				(type default)
			)
			(layer "F.SilkS")
		)
		(fp_line
			(start 0.7874 0.4064)
			(end -0.7874 0.4064)
			(stroke
				(width 0.1524)
				(type default)
			)
			(layer "F.SilkS")
		)
		(fp_line
			(start -0.7874 0.4064)
			(end -0.7874 -0.4064)
			(stroke
				(width 0.1524)
				(type default)
			)
			(layer "F.SilkS")
		)
		(fp_line
			(start -0.12065 -0.305054)
			(end -0.12065 -0.2794)
			(stroke
				(width 0.1)
				(type default)
			)
			(layer "F.Fab")
		)
		(fp_line
			(start -0.67945 -0.305054)
			(end -0.12065 -0.305054)
			(stroke
				(width 0.1)
				(type default)
			)
			(layer "F.Fab")
		)
		(fp_line
			(start 0.67945 -0.3048)
			(end 0.67945 0.3048)
			(stroke
				(width 0.1)
				(type default)
			)
			(layer "F.Fab")
		)
		(fp_line
			(start 0.12065 -0.3048)
			(end 0.67945 -0.3048)
			(stroke
				(width 0.1)
				(type default)
			)
			(layer "F.Fab")
		)
		(fp_line
			(start 0.12065 -0.2794)
			(end 0.12065 -0.3048)
			(stroke
				(width 0.1)
				(type default)
			)
			(layer "F.Fab")
		)
		(fp_line
			(start -0.12065 -0.2794)
			(end 0.12065 -0.2794)
			(stroke
				(width 0.1)
				(type default)
			)
			(layer "F.Fab")
		)
		(fp_line
			(start 0.120396 0.2794)
			(end -0.12065 0.2794)
			(stroke
				(width 0.1)
				(type default)
			)
			(layer "F.Fab")
		)
		(fp_line
			(start -0.12065 0.2794)
			(end -0.12065 0.3048)
			(stroke
				(width 0.1)
				(type default)
			)
			(layer "F.Fab")
		)
		(fp_line
			(start 0.67945 0.3048)
			(end 0.120396 0.3048)
			(stroke
				(width 0.1)
				(type default)
			)
			(layer "F.Fab")
		)
		(fp_line
			(start 0.120396 0.3048)
			(end 0.120396 0.2794)
			(stroke
				(width 0.1)
				(type default)
			)
			(layer "F.Fab")
		)
		(fp_line
			(start -0.12065 0.3048)
			(end -0.67945 0.3048)
			(stroke
				(width 0.1)
				(type default)
			)
			(layer "F.Fab")
		)
		(fp_line
			(start -0.67945 0.3048)
			(end -0.67945 -0.305054)
			(stroke
				(width 0.1)
				(type default)
			)
			(layer "F.Fab")
		)
		(pad "1" smd circle
			(at -0.40005 0 90)
			(size 0 0)
			(layers "F.Cu" "F.Mask" "F.Paste")
			(net "SSD7_PWR_EN_R")
		)
		(pad "2" smd circle
			(at 0.40005 0 90)
			(size 0 0)
			(layers "F.Cu" "F.Mask" "F.Paste")
			(net "P12V_SSD7_CO_EN")
		)
	)
	(footprint ""
		(layer "F.Cu")
		(at 112.311942 -108.737654 180)
		(property "Reference" "C840"
			(at 0 0 180)
			(layer "F.SilkS")
			(hide yes)
			(effects
				(font
					(size 1.27 1.27)
				)
			)
		)
		(property "Value" ""
			(at 0 0 180)
			(layer "F.Fab")
			(effects
				(font
					(size 1.27 1.27)
				)
			)
		)
		(duplicate_pad_numbers_are_jumpers no)
		(fp_line
			(start 0.7874 0.4064)
			(end -0.7874 0.4064)
			(stroke
				(width 0.1524)
				(type default)
			)
			(layer "F.SilkS")
		)
		(fp_line
			(start 0.7874 -0.4064)
			(end 0.7874 0.4064)
			(stroke
				(width 0.1524)
				(type default)
			)
			(layer "F.SilkS")
		)
		(fp_line
			(start -0.7874 0.4064)
			(end -0.7874 -0.4064)
			(stroke
				(width 0.1524)
				(type default)
			)
			(layer "F.SilkS")
		)
		(fp_line
			(start -0.7874 -0.4064)
			(end 0.7874 -0.4064)
			(stroke
				(width 0.1524)
				(type default)
			)
			(layer "F.SilkS")
		)
		(fp_line
			(start 0.67945 0.3048)
			(end 0.120396 0.3048)
			(stroke
				(width 0.1)
				(type default)
			)
			(layer "F.Fab")
		)
		(fp_line
			(start 0.67945 -0.3048)
			(end 0.67945 0.3048)
			(stroke
				(width 0.1)
				(type default)
			)
			(layer "F.Fab")
		)
		(fp_line
			(start 0.12065 -0.2794)
			(end 0.12065 -0.3048)
			(stroke
				(width 0.1)
				(type default)
			)
			(layer "F.Fab")
		)
		(fp_line
			(start 0.12065 -0.3048)
			(end 0.67945 -0.3048)
			(stroke
				(width 0.1)
				(type default)
			)
			(layer "F.Fab")
		)
		(fp_line
			(start 0.120396 0.3048)
			(end 0.120396 0.2794)
			(stroke
				(width 0.1)
				(type default)
			)
			(layer "F.Fab")
		)
		(fp_line
			(start 0.120396 0.2794)
			(end -0.12065 0.2794)
			(stroke
				(width 0.1)
				(type default)
			)
			(layer "F.Fab")
		)
		(fp_line
			(start -0.12065 0.3048)
			(end -0.67945 0.3048)
			(stroke
				(width 0.1)
				(type default)
			)
			(layer "F.Fab")
		)
		(fp_line
			(start -0.12065 0.2794)
			(end -0.12065 0.3048)
			(stroke
				(width 0.1)
				(type default)
			)
			(layer "F.Fab")
		)
		(fp_line
			(start -0.12065 -0.2794)
			(end 0.12065 -0.2794)
			(stroke
				(width 0.1)
				(type default)
			)
			(layer "F.Fab")
		)
		(fp_line
			(start -0.12065 -0.305054)
			(end -0.12065 -0.2794)
			(stroke
				(width 0.1)
				(type default)
			)
			(layer "F.Fab")
		)
		(fp_line
			(start -0.67945 0.3048)
			(end -0.67945 -0.305054)
			(stroke
				(width 0.1)
				(type default)
			)
			(layer "F.Fab")
		)
		(fp_line
			(start -0.67945 -0.305054)
			(end -0.12065 -0.305054)
			(stroke
				(width 0.1)
				(type default)
			)
			(layer "F.Fab")
		)
		(pad "1" smd circle
			(at -0.40005 0 180)
			(size 0 0)
			(layers "F.Cu" "F.Mask" "F.Paste")
			(net "GND")
		)
		(pad "2" smd circle
			(at 0.40005 0 180)
			(size 0 0)
			(layers "F.Cu" "F.Mask" "F.Paste")
			(net "P12V_NIC1_CO_EN")
		)
	)
	(footprint ""
		(layer "F.Cu")
		(at 345.057476 -313.620404)
		(property "Reference" "R5794"
			(at 0 0 0)
			(layer "F.SilkS")
			(hide yes)
			(effects
				(font
					(size 1.27 1.27)
				)
			)
		)
		(property "Value" ""
			(at 0 0 0)
			(layer "F.Fab")
			(effects
				(font
					(size 1.27 1.27)
				)
			)
		)
		(duplicate_pad_numbers_are_jumpers no)
		(fp_line
			(start -2.576322 -1.1303)
			(end 2.576322 -1.1303)
			(stroke
				(width 0.1524)
				(type default)
			)
			(layer "F.SilkS")
		)
		(fp_line
			(start -2.576322 1.1303)
			(end -2.576322 -1.1303)
			(stroke
				(width 0.1524)
				(type default)
			)
			(layer "F.SilkS")
		)
		(fp_line
			(start 2.576322 -1.1303)
			(end 2.576322 1.1303)
			(stroke
				(width 0.1524)
				(type default)
			)
			(layer "F.SilkS")
		)
		(fp_line
			(start 2.576322 1.1303)
			(end -2.576322 1.1303)
			(stroke
				(width 0.1524)
				(type default)
			)
			(layer "F.SilkS")
		)
		(fp_line
			(start -1.649984 -0.899922)
			(end -1.649984 0.899922)
			(stroke
				(width 0.1)
				(type default)
			)
			(layer "F.Fab")
		)
		(fp_line
			(start -1.649984 0.899922)
			(end 1.649984 0.899922)
			(stroke
				(width 0.1)
				(type default)
			)
			(layer "F.Fab")
		)
		(fp_line
			(start 1.649984 -0.899922)
			(end -1.649984 -0.899922)
			(stroke
				(width 0.1)
				(type default)
			)
			(layer "F.Fab")
		)
		(fp_line
			(start 1.649984 0.899922)
			(end 1.649984 -0.899922)
			(stroke
				(width 0.1)
				(type default)
			)
			(layer "F.Fab")
		)
		(pad "1A" smd rect
			(at -1.700022 0)
			(size 1.4986 2.0066)
			(layers "F.Cu" "F.Mask" "F.Paste")
			(net "P0V8_PEX2")
		)
		(pad "1B" smd rect
			(at -1.077722 0)
			(size 0.254 0.508)
			(layers "F.Cu" "F.Mask" "F.Paste")
			(net "P0V8_PEX2")
		)
		(pad "2A" smd rect
			(at 1.700022 0)
			(size 1.4986 2.0066)
			(layers "F.Cu" "F.Mask" "F.Paste")
			(net "P0V8_SERDES_VDDA_PEX2")
		)
		(pad "2B" smd rect
			(at 1.077722 0)
			(size 0.254 0.508)
			(layers "F.Cu" "F.Mask" "F.Paste")
			(net "P0V8_SERDES_VDDA_PEX2")
		)
	)
	(footprint ""
		(layer "F.Cu")
		(at 352.319844 -146.606768 180)
		(property "Reference" "R4845"
			(at 0 0 180)
			(layer "F.SilkS")
			(hide yes)
			(effects
				(font
					(size 1.27 1.27)
				)
			)
		)
		(property "Value" ""
			(at 0 0 180)
			(layer "F.Fab")
			(effects
				(font
					(size 1.27 1.27)
				)
			)
		)
		(duplicate_pad_numbers_are_jumpers no)
		(fp_line
			(start 0.7874 0.4064)
			(end -0.7874 0.4064)
			(stroke
				(width 0.1524)
				(type default)
			)
			(layer "F.SilkS")
		)
		(fp_line
			(start 0.7874 -0.4064)
			(end 0.7874 0.4064)
			(stroke
				(width 0.1524)
				(type default)
			)
			(layer "F.SilkS")
		)
		(fp_line
			(start -0.7874 0.4064)
			(end -0.7874 -0.4064)
			(stroke
				(width 0.1524)
				(type default)
			)
			(layer "F.SilkS")
		)
		(fp_line
			(start -0.7874 -0.4064)
			(end 0.7874 -0.4064)
			(stroke
				(width 0.1524)
				(type default)
			)
			(layer "F.SilkS")
		)
		(fp_line
			(start 0.67945 0.3048)
			(end 0.120396 0.3048)
			(stroke
				(width 0.1)
				(type default)
			)
			(layer "F.Fab")
		)
		(fp_line
			(start 0.67945 -0.3048)
			(end 0.67945 0.3048)
			(stroke
				(width 0.1)
				(type default)
			)
			(layer "F.Fab")
		)
		(fp_line
			(start 0.12065 -0.2794)
			(end 0.12065 -0.3048)
			(stroke
				(width 0.1)
				(type default)
			)
			(layer "F.Fab")
		)
		(fp_line
			(start 0.12065 -0.3048)
			(end 0.67945 -0.3048)
			(stroke
				(width 0.1)
				(type default)
			)
			(layer "F.Fab")
		)
		(fp_line
			(start 0.120396 0.3048)
			(end 0.120396 0.2794)
			(stroke
				(width 0.1)
				(type default)
			)
			(layer "F.Fab")
		)
		(fp_line
			(start 0.120396 0.2794)
			(end -0.12065 0.2794)
			(stroke
				(width 0.1)
				(type default)
			)
			(layer "F.Fab")
		)
		(fp_line
			(start -0.12065 0.3048)
			(end -0.67945 0.3048)
			(stroke
				(width 0.1)
				(type default)
			)
			(layer "F.Fab")
		)
		(fp_line
			(start -0.12065 0.2794)
			(end -0.12065 0.3048)
			(stroke
				(width 0.1)
				(type default)
			)
			(layer "F.Fab")
		)
		(fp_line
			(start -0.12065 -0.2794)
			(end 0.12065 -0.2794)
			(stroke
				(width 0.1)
				(type default)
			)
			(layer "F.Fab")
		)
		(fp_line
			(start -0.12065 -0.305054)
			(end -0.12065 -0.2794)
			(stroke
				(width 0.1)
				(type default)
			)
			(layer "F.Fab")
		)
		(fp_line
			(start -0.67945 0.3048)
			(end -0.67945 -0.305054)
			(stroke
				(width 0.1)
				(type default)
			)
			(layer "F.Fab")
		)
		(fp_line
			(start -0.67945 -0.305054)
			(end -0.12065 -0.305054)
			(stroke
				(width 0.1)
				(type default)
			)
			(layer "F.Fab")
		)
		(pad "1" smd circle
			(at -0.40005 0 180)
			(size 0 0)
			(layers "F.Cu" "F.Mask" "F.Paste")
			(net "GND")
		)
		(pad "2" smd circle
			(at 0.40005 0 180)
			(size 0 0)
			(layers "F.Cu" "F.Mask" "F.Paste")
			(net "PCA9555_1_PEX3_A0")
		)
	)
	(footprint ""
		(layer "F.Cu")
		(at 58.11901 -59.574684 90)
		(property "Reference" "PC517"
			(at 0 0 90)
			(layer "F.SilkS")
			(hide yes)
			(effects
				(font
					(size 1.27 1.27)
				)
			)
		)
		(property "Value" ""
			(at 0 0 90)
			(layer "F.Fab")
			(effects
				(font
					(size 1.27 1.27)
				)
			)
		)
		(duplicate_pad_numbers_are_jumpers no)
		(fp_line
			(start 0.7874 -0.4064)
			(end 0.7874 0.4064)
			(stroke
				(width 0.1524)
				(type default)
			)
			(layer "F.SilkS")
		)
		(fp_line
			(start -0.7874 -0.4064)
			(end 0.7874 -0.4064)
			(stroke
				(width 0.1524)
				(type default)
			)
			(layer "F.SilkS")
		)
		(fp_line
			(start 0.7874 0.4064)
			(end -0.7874 0.4064)
			(stroke
				(width 0.1524)
				(type default)
			)
			(layer "F.SilkS")
		)
		(fp_line
			(start -0.7874 0.4064)
			(end -0.7874 -0.4064)
			(stroke
				(width 0.1524)
				(type default)
			)
			(layer "F.SilkS")
		)
		(fp_line
			(start -0.12065 -0.305054)
			(end -0.12065 -0.2794)
			(stroke
				(width 0.1)
				(type default)
			)
			(layer "F.Fab")
		)
		(fp_line
			(start -0.67945 -0.305054)
			(end -0.12065 -0.305054)
			(stroke
				(width 0.1)
				(type default)
			)
			(layer "F.Fab")
		)
		(fp_line
			(start 0.67945 -0.3048)
			(end 0.67945 0.3048)
			(stroke
				(width 0.1)
				(type default)
			)
			(layer "F.Fab")
		)
		(fp_line
			(start 0.12065 -0.3048)
			(end 0.67945 -0.3048)
			(stroke
				(width 0.1)
				(type default)
			)
			(layer "F.Fab")
		)
		(fp_line
			(start 0.12065 -0.2794)
			(end 0.12065 -0.3048)
			(stroke
				(width 0.1)
				(type default)
			)
			(layer "F.Fab")
		)
		(fp_line
			(start -0.12065 -0.2794)
			(end 0.12065 -0.2794)
			(stroke
				(width 0.1)
				(type default)
			)
			(layer "F.Fab")
		)
		(fp_line
			(start 0.120396 0.2794)
			(end -0.12065 0.2794)
			(stroke
				(width 0.1)
				(type default)
			)
			(layer "F.Fab")
		)
		(fp_line
			(start -0.12065 0.2794)
			(end -0.12065 0.3048)
			(stroke
				(width 0.1)
				(type default)
			)
			(layer "F.Fab")
		)
		(fp_line
			(start 0.67945 0.3048)
			(end 0.120396 0.3048)
			(stroke
				(width 0.1)
				(type default)
			)
			(layer "F.Fab")
		)
		(fp_line
			(start 0.120396 0.3048)
			(end 0.120396 0.2794)
			(stroke
				(width 0.1)
				(type default)
			)
			(layer "F.Fab")
		)
		(fp_line
			(start -0.12065 0.3048)
			(end -0.67945 0.3048)
			(stroke
				(width 0.1)
				(type default)
			)
			(layer "F.Fab")
		)
		(fp_line
			(start -0.67945 0.3048)
			(end -0.67945 -0.305054)
			(stroke
				(width 0.1)
				(type default)
			)
			(layer "F.Fab")
		)
		(pad "1" smd circle
			(at -0.40005 0 90)
			(size 0 0)
			(layers "F.Cu" "F.Mask" "F.Paste")
			(net "P5V_AUX")
		)
		(pad "2" smd circle
			(at 0.40005 0 90)
			(size 0 0)
			(layers "F.Cu" "F.Mask" "F.Paste")
			(net "GND")
		)
	)
)
